# S9S_MB_2U (Grand Teton) — schematic netlist excerpt (pin names and nets, part order shuffled) for the footprints in the layout excerpt that follows; sources: Cadence DE-HDL packaged netlist, KiCad conversion of 03242023_DA0F0TMBIJ0_F0T_Motherboard_J_brd_V01_OCP.brd

PC1682  Q_CAP  22UF 16V 20% X6S  pkg C0805  page 290 : A = SW_P12V_PVCCFA_EHV_FIVRA_CPU1_R ; B = GND
R4172  Q_RES  33.2 1% CHIP  pkg 0402LF  page 215 : A = GPU_3V3IO_RSVD4_ISO ; B = GPU_3V3IO_RSVD4_ISO_R
C429  Q_CAP  22UF 4V 20% X6S  pkg C0402  page 77 : A = PVCCD_HV_CPU1 ; B = GND

(kicad_pcb
	(version 20260206)
	(generator "pcbnew")
	(generator_version "10.0")
	(general
		(thickness 1.6)
		(legacy_teardrops no)
	)
	(paper "A4")
	(title_block
		(title "03242023_DA0F0TMBIJ0_F0T_Motherboard_J_brd_V01_OCP.brd")
		(comment 1 "Grand Teton / footprints 587-589 of 6105")
	)
	(layers
		(0 "F.Cu" signal "TOP")
		(4 "In1.Cu" signal "GND")
		(6 "In2.Cu" signal "IN1")
		(8 "In3.Cu" signal "GND1")
		(10 "In4.Cu" signal "IN2")
		(12 "In5.Cu" signal "GND2")
		(14 "In6.Cu" signal "IN3")
		(16 "In7.Cu" signal "GND3")
		(18 "In8.Cu" signal "VCC")
		(20 "In9.Cu" signal "VCC1")
		(22 "In10.Cu" signal "GND4")
		(24 "In11.Cu" signal "IN4")
		(26 "In12.Cu" signal "GND5")
		(28 "In13.Cu" signal "IN5")
		(30 "In14.Cu" signal "GND6")
		(32 "In15.Cu" signal "IN6")
		(34 "In16.Cu" signal "GND7")
		(2 "B.Cu" signal "BOTTOM")
		(9 "F.Adhes" user "F.Adhesive")
		(11 "B.Adhes" user "B.Adhesive")
		(13 "F.Paste" user "Package Geometry/Pastemask Top")
		(15 "B.Paste" user "Package Geometry/Pastemask Bottom")
		(5 "F.SilkS" user "Ref Des/Silkscreen Top")
		(7 "B.SilkS" user "Ref Des/Silkscreen Bottom")
		(1 "F.Mask" user "Board Geometry/Soldermask Top")
		(3 "B.Mask" user "Board Geometry/Soldermask Bottom")
		(17 "Dwgs.User" user "User.Drawings")
		(19 "Cmts.User" user "User.Comments")
		(21 "Eco1.User" user "User.Eco1")
		(23 "Eco2.User" user "User.Eco2")
		(25 "Edge.Cuts" user "Board Geometry/Outline")
		(27 "Margin" user)
		(31 "F.CrtYd" user "Package Geometry/Place Bound Top")
		(29 "B.CrtYd" user "Package Geometry/Place Bound Bottom")
		(35 "F.Fab" user "Ref Des/Assembly Top")
		(33 "B.Fab" user "Ref Des/Assembly Bottom")
	)
	(footprint ""
		(layer "F.Cu")
		(at 119.508016 -245.634256 -90)
		(property "Reference" "C429"
			(at 0 0 270)
			(layer "F.SilkS")
			(hide yes)
			(effects
				(font
					(size 1.27 1.27)
				)
			)
		)
		(property "Value" ""
			(at 0 0 270)
			(layer "F.Fab")
			(effects
				(font
					(size 1.27 1.27)
				)
			)
		)
		(duplicate_pad_numbers_are_jumpers no)
		(fp_line
			(start -0.7874 0.4064)
			(end -0.7874 -0.4064)
			(stroke
				(width 0.1524)
				(type default)
			)
			(layer "F.SilkS")
		)
		(fp_line
			(start 0.7874 0.4064)
			(end -0.7874 0.4064)
			(stroke
				(width 0.1524)
				(type default)
			)
			(layer "F.SilkS")
		)
		(fp_line
			(start -0.7874 -0.4064)
			(end 0.7874 -0.4064)
			(stroke
				(width 0.1524)
				(type default)
			)
			(layer "F.SilkS")
		)
		(fp_line
			(start 0.7874 -0.4064)
			(end 0.7874 0.4064)
			(stroke
				(width 0.1524)
				(type default)
			)
			(layer "F.SilkS")
		)
		(fp_line
			(start -0.67945 0.3048)
			(end -0.67945 -0.305054)
			(stroke
				(width 0.1)
				(type default)
			)
			(layer "F.Fab")
		)
		(fp_line
			(start -0.12065 0.3048)
			(end -0.67945 0.3048)
			(stroke
				(width 0.1)
				(type default)
			)
			(layer "F.Fab")
		)
		(fp_line
			(start 0.120396 0.3048)
			(end 0.120396 0.2794)
			(stroke
				(width 0.1)
				(type default)
			)
			(layer "F.Fab")
		)
		(fp_line
			(start 0.67945 0.3048)
			(end 0.120396 0.3048)
			(stroke
				(width 0.1)
				(type default)
			)
			(layer "F.Fab")
		)
		(fp_line
			(start -0.12065 0.2794)
			(end -0.12065 0.3048)
			(stroke
				(width 0.1)
				(type default)
			)
			(layer "F.Fab")
		)
		(fp_line
			(start 0.120396 0.2794)
			(end -0.12065 0.2794)
			(stroke
				(width 0.1)
				(type default)
			)
			(layer "F.Fab")
		)
		(fp_line
			(start -0.12065 -0.2794)
			(end 0.12065 -0.2794)
			(stroke
				(width 0.1)
				(type default)
			)
			(layer "F.Fab")
		)
		(fp_line
			(start 0.12065 -0.2794)
			(end 0.12065 -0.3048)
			(stroke
				(width 0.1)
				(type default)
			)
			(layer "F.Fab")
		)
		(fp_line
			(start 0.12065 -0.3048)
			(end 0.67945 -0.3048)
			(stroke
				(width 0.1)
				(type default)
			)
			(layer "F.Fab")
		)
		(fp_line
			(start 0.67945 -0.3048)
			(end 0.67945 0.3048)
			(stroke
				(width 0.1)
				(type default)
			)
			(layer "F.Fab")
		)
		(fp_line
			(start -0.67945 -0.305054)
			(end -0.12065 -0.305054)
			(stroke
				(width 0.1)
				(type default)
			)
			(layer "F.Fab")
		)
		(fp_line
			(start -0.12065 -0.305054)
			(end -0.12065 -0.2794)
			(stroke
				(width 0.1)
				(type default)
			)
			(layer "F.Fab")
		)
		(pad "1" smd circle
			(at -0.40005 0 270)
			(size 0 0)
			(layers "F.Cu" "F.Mask" "F.Paste")
			(net "PVCCD_HV_CPU1")
		)
		(pad "2" smd circle
			(at 0.40005 0 270)
			(size 0 0)
			(layers "F.Cu" "F.Mask" "F.Paste")
			(net "GND")
		)
	)
	(footprint ""
		(layer "F.Cu")
		(at 204.93736 -116.804948 180)
		(property "Reference" "R4172"
			(at 0 0 180)
			(layer "F.SilkS")
			(hide yes)
			(effects
				(font
					(size 1.27 1.27)
				)
			)
		)
		(property "Value" ""
			(at 0 0 180)
			(layer "F.Fab")
			(effects
				(font
					(size 1.27 1.27)
				)
			)
		)
		(duplicate_pad_numbers_are_jumpers no)
		(fp_line
			(start 0.7874 0.4064)
			(end -0.7874 0.4064)
			(stroke
				(width 0.1524)
				(type default)
			)
			(layer "F.SilkS")
		)
		(fp_line
			(start 0.7874 -0.4064)
			(end 0.7874 0.4064)
			(stroke
				(width 0.1524)
				(type default)
			)
			(layer "F.SilkS")
		)
		(fp_line
			(start -0.7874 0.4064)
			(end -0.7874 -0.4064)
			(stroke
				(width 0.1524)
				(type default)
			)
			(layer "F.SilkS")
		)
		(fp_line
			(start -0.7874 -0.4064)
			(end 0.7874 -0.4064)
			(stroke
				(width 0.1524)
				(type default)
			)
			(layer "F.SilkS")
		)
		(fp_line
			(start 0.67945 0.3048)
			(end 0.120396 0.3048)
			(stroke
				(width 0.1)
				(type default)
			)
			(layer "F.Fab")
		)
		(fp_line
			(start 0.67945 -0.3048)
			(end 0.67945 0.3048)
			(stroke
				(width 0.1)
				(type default)
			)
			(layer "F.Fab")
		)
		(fp_line
			(start 0.12065 -0.2794)
			(end 0.12065 -0.3048)
			(stroke
				(width 0.1)
				(type default)
			)
			(layer "F.Fab")
		)
		(fp_line
			(start 0.12065 -0.3048)
			(end 0.67945 -0.3048)
			(stroke
				(width 0.1)
				(type default)
			)
			(layer "F.Fab")
		)
		(fp_line
			(start 0.120396 0.3048)
			(end 0.120396 0.2794)
			(stroke
				(width 0.1)
				(type default)
			)
			(layer "F.Fab")
		)
		(fp_line
			(start 0.120396 0.2794)
			(end -0.12065 0.2794)
			(stroke
				(width 0.1)
				(type default)
			)
			(layer "F.Fab")
		)
		(fp_line
			(start -0.12065 0.3048)
			(end -0.67945 0.3048)
			(stroke
				(width 0.1)
				(type default)
			)
			(layer "F.Fab")
		)
		(fp_line
			(start -0.12065 0.2794)
			(end -0.12065 0.3048)
			(stroke
				(width 0.1)
				(type default)
			)
			(layer "F.Fab")
		)
		(fp_line
			(start -0.12065 -0.2794)
			(end 0.12065 -0.2794)
			(stroke
				(width 0.1)
				(type default)
			)
			(layer "F.Fab")
		)
		(fp_line
			(start -0.12065 -0.305054)
			(end -0.12065 -0.2794)
			(stroke
				(width 0.1)
				(type default)
			)
			(layer "F.Fab")
		)
		(fp_line
			(start -0.67945 0.3048)
			(end -0.67945 -0.305054)
			(stroke
				(width 0.1)
				(type default)
			)
			(layer "F.Fab")
		)
		(fp_line
			(start -0.67945 -0.305054)
			(end -0.12065 -0.305054)
			(stroke
				(width 0.1)
				(type default)
			)
			(layer "F.Fab")
		)
		(pad "1" smd circle
			(at -0.40005 0 180)
			(size 0 0)
			(layers "F.Cu" "F.Mask" "F.Paste")
			(net "GPU_3V3IO_RSVD4_ISO")
		)
		(pad "2" smd circle
			(at 0.40005 0 180)
			(size 0 0)
			(layers "F.Cu" "F.Mask" "F.Paste")
			(net "GPU_3V3IO_RSVD4_ISO_R")
		)
	)
	(footprint ""
		(layer "F.Cu")
		(at 186.87034 -360.26471)
		(property "Reference" "PC1682"
			(at 0 0 0)
			(layer "F.SilkS")
			(hide yes)
			(effects
				(font
					(size 1.27 1.27)
				)
			)
		)
		(property "Value" ""
			(at 0 0 0)
			(layer "F.Fab")
			(effects
				(font
					(size 1.27 1.27)
				)
			)
		)
		(duplicate_pad_numbers_are_jumpers no)
		(fp_line
			(start -1.524 -0.762)
			(end 1.524 -0.762)
			(stroke
				(width 0.1524)
				(type default)
			)
			(layer "F.SilkS")
		)
		(fp_line
			(start -1.524 0.762)
			(end -1.524 -0.762)
			(stroke
				(width 0.1524)
				(type default)
			)
			(layer "F.SilkS")
		)
		(fp_line
			(start 1.524 -0.762)
			(end 1.524 0.762)
			(stroke
				(width 0.1524)
				(type default)
			)
			(layer "F.SilkS")
		)
		(fp_line
			(start 1.524 0.762)
			(end -1.524 0.762)
			(stroke
				(width 0.1524)
				(type default)
			)
			(layer "F.SilkS")
		)
		(fp_line
			(start -1.1049 -0.724916)
			(end -1.1049 0.724916)
			(stroke
				(width 0.1)
				(type default)
			)
			(layer "F.Fab")
		)
		(fp_line
			(start -1.1049 0.724916)
			(end 1.1049 0.724916)
			(stroke
				(width 0.1)
				(type default)
			)
			(layer "F.Fab")
		)
		(fp_line
			(start 1.1049 -0.724916)
			(end -1.1049 -0.724916)
			(stroke
				(width 0.1)
				(type default)
			)
			(layer "F.Fab")
		)
		(fp_line
			(start 1.1049 0.724916)
			(end 1.1049 -0.724916)
			(stroke
				(width 0.1)
				(type default)
			)
			(layer "F.Fab")
		)
		(pad "1" smd rect
			(at -0.889 0 180)
			(size 1.016 1.27)
			(layers "F.Cu" "F.Mask" "F.Paste")
			(net "SW_P12V_PVCCFA_EHV_FIVRA_CPU1_R")
		)
		(pad "2" smd rect
			(at 0.889 0 180)
			(size 1.016 1.27)
			(layers "F.Cu" "F.Mask" "F.Paste")
			(net "GND")
		)
	)
)
